(kicad_pcb
	(version 20260206)
	(generator "pcbnew")
	(generator_version "10.0")
	(general
		(thickness 1.6)
		(legacy_teardrops no)
	)
	(paper "A4")
	(title_block
		(title "03242023_DA0F0TMBIJ0_F0T_Motherboard_J_brd_V01_OCP.brd")
		(comment 1 "Grand Teton / footprints 4925-4929 of 6105")
	)
	(layers
		(0 "F.Cu" signal "TOP")
		(4 "In1.Cu" signal "GND")
		(6 "In2.Cu" signal "IN1")
		(8 "In3.Cu" signal "GND1")
		(10 "In4.Cu" signal "IN2")
		(12 "In5.Cu" signal "GND2")
		(14 "In6.Cu" signal "IN3")
		(16 "In7.Cu" signal "GND3")
		(18 "In8.Cu" signal "VCC")
		(20 "In9.Cu" signal "VCC1")
		(22 "In10.Cu" signal "GND4")
		(24 "In11.Cu" signal "IN4")
		(26 "In12.Cu" signal "GND5")
		(28 "In13.Cu" signal "IN5")
		(30 "In14.Cu" signal "GND6")
		(32 "In15.Cu" signal "IN6")
		(34 "In16.Cu" signal "GND7")
		(2 "B.Cu" signal "BOTTOM")
		(9 "F.Adhes" user "F.Adhesive")
		(11 "B.Adhes" user "B.Adhesive")
		(13 "F.Paste" user "Package Geometry/Pastemask Top")
		(15 "B.Paste" user "Package Geometry/Pastemask Bottom")
		(5 "F.SilkS" user "Ref Des/Silkscreen Top")
		(7 "B.SilkS" user "Ref Des/Silkscreen Bottom")
		(1 "F.Mask" user "Board Geometry/Soldermask Top")
		(3 "B.Mask" user "Board Geometry/Soldermask Bottom")
		(17 "Dwgs.User" user "User.Drawings")
		(19 "Cmts.User" user "User.Comments")
		(21 "Eco1.User" user "User.Eco1")
		(23 "Eco2.User" user "User.Eco2")
		(25 "Edge.Cuts" user "Board Geometry/Outline")
		(27 "Margin" user)
		(31 "F.CrtYd" user "Package Geometry/Place Bound Top")
		(29 "B.CrtYd" user "Package Geometry/Place Bound Bottom")
		(35 "F.Fab" user "Ref Des/Assembly Top")
		(33 "B.Fab" user "Ref Des/Assembly Bottom")
	)
	(footprint ""
		(layer "B.Cu")
		(at 181.86146 -18.710148 90)
		(property "Reference" "R2419"
			(at 0 0 90)
			(layer "B.SilkS")
			(hide yes)
			(effects
				(font
					(size 1.27 1.27)
				)
				(justify mirror)
			)
		)
		(property "Value" ""
			(at 0 0 90)
			(layer "B.Fab")
			(effects
				(font
					(size 1.27 1.27)
				)
				(justify mirror)
			)
		)
		(duplicate_pad_numbers_are_jumpers no)
		(fp_line
			(start 0.7874 -0.4064)
			(end -0.7874 -0.4064)
			(stroke
				(width 0.1524)
				(type default)
			)
			(layer "B.SilkS")
		)
		(fp_line
			(start -0.7874 -0.4064)
			(end -0.7874 0.4064)
			(stroke
				(width 0.1524)
				(type default)
			)
			(layer "B.SilkS")
		)
		(fp_line
			(start 0.7874 0.4064)
			(end 0.7874 -0.4064)
			(stroke
				(width 0.1524)
				(type default)
			)
			(layer "B.SilkS")
		)
		(fp_line
			(start -0.7874 0.4064)
			(end 0.7874 0.4064)
			(stroke
				(width 0.1524)
				(type default)
			)
			(layer "B.SilkS")
		)
		(fp_line
			(start 0.67945 -0.305054)
			(end 0.12065 -0.305054)
			(stroke
				(width 0.1)
				(type default)
			)
			(layer "B.Fab")
		)
		(fp_line
			(start 0.12065 -0.305054)
			(end 0.12065 -0.2794)
			(stroke
				(width 0.1)
				(type default)
			)
			(layer "B.Fab")
		)
		(fp_line
			(start -0.12065 -0.3048)
			(end -0.67945 -0.3048)
			(stroke
				(width 0.1)
				(type default)
			)
			(layer "B.Fab")
		)
		(fp_line
			(start -0.67945 -0.3048)
			(end -0.67945 0.3048)
			(stroke
				(width 0.1)
				(type default)
			)
			(layer "B.Fab")
		)
		(fp_line
			(start 0.12065 -0.2794)
			(end -0.12065 -0.2794)
			(stroke
				(width 0.1)
				(type default)
			)
			(layer "B.Fab")
		)
		(fp_line
			(start -0.12065 -0.2794)
			(end -0.12065 -0.3048)
			(stroke
				(width 0.1)
				(type default)
			)
			(layer "B.Fab")
		)
		(fp_line
			(start 0.12065 0.2794)
			(end 0.12065 0.3048)
			(stroke
				(width 0.1)
				(type default)
			)
			(layer "B.Fab")
		)
		(fp_line
			(start -0.120396 0.2794)
			(end 0.12065 0.2794)
			(stroke
				(width 0.1)
				(type default)
			)
			(layer "B.Fab")
		)
		(fp_line
			(start 0.67945 0.3048)
			(end 0.67945 -0.305054)
			(stroke
				(width 0.1)
				(type default)
			)
			(layer "B.Fab")
		)
		(fp_line
			(start 0.12065 0.3048)
			(end 0.67945 0.3048)
			(stroke
				(width 0.1)
				(type default)
			)
			(layer "B.Fab")
		)
		(fp_line
			(start -0.120396 0.3048)
			(end -0.120396 0.2794)
			(stroke
				(width 0.1)
				(type default)
			)
			(layer "B.Fab")
		)
		(fp_line
			(start -0.67945 0.3048)
			(end -0.120396 0.3048)
			(stroke
				(width 0.1)
				(type default)
			)
			(layer "B.Fab")
		)
		(pad "1" smd circle
			(at 0.40005 0 270)
			(size 0 0)
			(layers "B.Cu" "B.Mask" "B.Paste")
			(net "SMB_HOST_3V3AUX_SCL")
		)
		(pad "2" smd circle
			(at -0.40005 0 270)
			(size 0 0)
			(layers "B.Cu" "B.Mask" "B.Paste")
			(net "SMB_HOST_3V3AUX_SCL_R0")
		)
	)
	(footprint ""
		(layer "B.Cu")
		(at 82.462624 -184.096152 90)
		(property "Reference" "R337"
			(at 0 0 90)
			(layer "B.SilkS")
			(hide yes)
			(effects
				(font
					(size 1.27 1.27)
				)
				(justify mirror)
			)
		)
		(property "Value" ""
			(at 0 0 90)
			(layer "B.Fab")
			(effects
				(font
					(size 1.27 1.27)
				)
				(justify mirror)
			)
		)
		(duplicate_pad_numbers_are_jumpers no)
		(fp_line
			(start 0.7874 -0.4064)
			(end -0.7874 -0.4064)
			(stroke
				(width 0.1524)
				(type default)
			)
			(layer "B.SilkS")
		)
		(fp_line
			(start -0.7874 -0.4064)
			(end -0.7874 0.4064)
			(stroke
				(width 0.1524)
				(type default)
			)
			(layer "B.SilkS")
		)
		(fp_line
			(start 0.7874 0.4064)
			(end 0.7874 -0.4064)
			(stroke
				(width 0.1524)
				(type default)
			)
			(layer "B.SilkS")
		)
		(fp_line
			(start -0.7874 0.4064)
			(end 0.7874 0.4064)
			(stroke
				(width 0.1524)
				(type default)
			)
			(layer "B.SilkS")
		)
		(fp_line
			(start 0.67945 -0.305054)
			(end 0.12065 -0.305054)
			(stroke
				(width 0.1)
				(type default)
			)
			(layer "B.Fab")
		)
		(fp_line
			(start 0.12065 -0.305054)
			(end 0.12065 -0.2794)
			(stroke
				(width 0.1)
				(type default)
			)
			(layer "B.Fab")
		)
		(fp_line
			(start -0.12065 -0.3048)
			(end -0.67945 -0.3048)
			(stroke
				(width 0.1)
				(type default)
			)
			(layer "B.Fab")
		)
		(fp_line
			(start -0.67945 -0.3048)
			(end -0.67945 0.3048)
			(stroke
				(width 0.1)
				(type default)
			)
			(layer "B.Fab")
		)
		(fp_line
			(start 0.12065 -0.2794)
			(end -0.12065 -0.2794)
			(stroke
				(width 0.1)
				(type default)
			)
			(layer "B.Fab")
		)
		(fp_line
			(start -0.12065 -0.2794)
			(end -0.12065 -0.3048)
			(stroke
				(width 0.1)
				(type default)
			)
			(layer "B.Fab")
		)
		(fp_line
			(start 0.12065 0.2794)
			(end 0.12065 0.3048)
			(stroke
				(width 0.1)
				(type default)
			)
			(layer "B.Fab")
		)
		(fp_line
			(start -0.120396 0.2794)
			(end 0.12065 0.2794)
			(stroke
				(width 0.1)
				(type default)
			)
			(layer "B.Fab")
		)
		(fp_line
			(start 0.67945 0.3048)
			(end 0.67945 -0.305054)
			(stroke
				(width 0.1)
				(type default)
			)
			(layer "B.Fab")
		)
		(fp_line
			(start 0.12065 0.3048)
			(end 0.67945 0.3048)
			(stroke
				(width 0.1)
				(type default)
			)
			(layer "B.Fab")
		)
		(fp_line
			(start -0.120396 0.3048)
			(end -0.120396 0.2794)
			(stroke
				(width 0.1)
				(type default)
			)
			(layer "B.Fab")
		)
		(fp_line
			(start -0.67945 0.3048)
			(end -0.120396 0.3048)
			(stroke
				(width 0.1)
				(type default)
			)
			(layer "B.Fab")
		)
		(pad "1" smd circle
			(at 0.40005 0 270)
			(size 0 0)
			(layers "B.Cu" "B.Mask" "B.Paste")
			(net "H_CPU1_ERR0_LVC1_R_N")
		)
		(pad "2" smd circle
			(at -0.40005 0 270)
			(size 0 0)
			(layers "B.Cu" "B.Mask" "B.Paste")
			(net "H_CPU_ERR0_LVC1_R_N")
		)
	)
	(footprint ""
		(layer "B.Cu")
		(at 293.544498 -400.999452 -90)
		(property "Reference" "PR2523"
			(at 0 0 90)
			(layer "B.SilkS")
			(hide yes)
			(effects
				(font
					(size 1.27 1.27)
				)
				(justify mirror)
			)
		)
		(property "Value" ""
			(at 0 0 90)
			(layer "B.Fab")
			(effects
				(font
					(size 1.27 1.27)
				)
				(justify mirror)
			)
		)
		(duplicate_pad_numbers_are_jumpers no)
		(fp_line
			(start -0.7874 0.4064)
			(end 0.7874 0.4064)
			(stroke
				(width 0.1524)
				(type default)
			)
			(layer "B.SilkS")
		)
		(fp_line
			(start 0.7874 0.4064)
			(end 0.7874 -0.4064)
			(stroke
				(width 0.1524)
				(type default)
			)
			(layer "B.SilkS")
		)
		(fp_line
			(start -0.7874 -0.4064)
			(end -0.7874 0.4064)
			(stroke
				(width 0.1524)
				(type default)
			)
			(layer "B.SilkS")
		)
		(fp_line
			(start 0.7874 -0.4064)
			(end -0.7874 -0.4064)
			(stroke
				(width 0.1524)
				(type default)
			)
			(layer "B.SilkS")
		)
		(fp_line
			(start -0.67945 0.3048)
			(end -0.120396 0.3048)
			(stroke
				(width 0.1)
				(type default)
			)
			(layer "B.Fab")
		)
		(fp_line
			(start -0.120396 0.3048)
			(end -0.120396 0.2794)
			(stroke
				(width 0.1)
				(type default)
			)
			(layer "B.Fab")
		)
		(fp_line
			(start 0.12065 0.3048)
			(end 0.67945 0.3048)
			(stroke
				(width 0.1)
				(type default)
			)
			(layer "B.Fab")
		)
		(fp_line
			(start 0.67945 0.3048)
			(end 0.67945 -0.305054)
			(stroke
				(width 0.1)
				(type default)
			)
			(layer "B.Fab")
		)
		(fp_line
			(start -0.120396 0.2794)
			(end 0.12065 0.2794)
			(stroke
				(width 0.1)
				(type default)
			)
			(layer "B.Fab")
		)
		(fp_line
			(start 0.12065 0.2794)
			(end 0.12065 0.3048)
			(stroke
				(width 0.1)
				(type default)
			)
			(layer "B.Fab")
		)
		(fp_line
			(start -0.12065 -0.2794)
			(end -0.12065 -0.3048)
			(stroke
				(width 0.1)
				(type default)
			)
			(layer "B.Fab")
		)
		(fp_line
			(start 0.12065 -0.2794)
			(end -0.12065 -0.2794)
			(stroke
				(width 0.1)
				(type default)
			)
			(layer "B.Fab")
		)
		(fp_line
			(start -0.67945 -0.3048)
			(end -0.67945 0.3048)
			(stroke
				(width 0.1)
				(type default)
			)
			(layer "B.Fab")
		)
		(fp_line
			(start -0.12065 -0.3048)
			(end -0.67945 -0.3048)
			(stroke
				(width 0.1)
				(type default)
			)
			(layer "B.Fab")
		)
		(fp_line
			(start 0.12065 -0.305054)
			(end 0.12065 -0.2794)
			(stroke
				(width 0.1)
				(type default)
			)
			(layer "B.Fab")
		)
		(fp_line
			(start 0.67945 -0.305054)
			(end 0.12065 -0.305054)
			(stroke
				(width 0.1)
				(type default)
			)
			(layer "B.Fab")
		)
		(pad "1" smd circle
			(at 0.40005 0 90)
			(size 0 0)
			(layers "B.Cu" "B.Mask" "B.Paste")
			(net "P12V_HSC_SENSE2_P")
		)
		(pad "2" smd circle
			(at -0.40005 0 90)
			(size 0 0)
			(layers "B.Cu" "B.Mask" "B.Paste")
			(net "P12V_HSC_SENSE2_R4_P")
		)
	)
	(footprint ""
		(layer "B.Cu")
		(at 361.691174 -361.759246)
		(property "Reference" "PR156"
			(at 0 0 0)
			(layer "B.SilkS")
			(hide yes)
			(effects
				(font
					(size 1.27 1.27)
				)
				(justify mirror)
			)
		)
		(property "Value" ""
			(at 0 0 0)
			(layer "B.Fab")
			(effects
				(font
					(size 1.27 1.27)
				)
				(justify mirror)
			)
		)
		(duplicate_pad_numbers_are_jumpers no)
		(fp_line
			(start -0.7874 -0.4064)
			(end -0.7874 0.4064)
			(stroke
				(width 0.1524)
				(type default)
			)
			(layer "B.SilkS")
		)
		(fp_line
			(start -0.7874 0.4064)
			(end 0.7874 0.4064)
			(stroke
				(width 0.1524)
				(type default)
			)
			(layer "B.SilkS")
		)
		(fp_line
			(start 0.7874 -0.4064)
			(end -0.7874 -0.4064)
			(stroke
				(width 0.1524)
				(type default)
			)
			(layer "B.SilkS")
		)
		(fp_line
			(start 0.7874 0.4064)
			(end 0.7874 -0.4064)
			(stroke
				(width 0.1524)
				(type default)
			)
			(layer "B.SilkS")
		)
		(fp_line
			(start -0.67945 -0.3048)
			(end -0.67945 0.3048)
			(stroke
				(width 0.1)
				(type default)
			)
			(layer "B.Fab")
		)
		(fp_line
			(start -0.67945 0.3048)
			(end -0.120396 0.3048)
			(stroke
				(width 0.1)
				(type default)
			)
			(layer "B.Fab")
		)
		(fp_line
			(start -0.12065 -0.3048)
			(end -0.67945 -0.3048)
			(stroke
				(width 0.1)
				(type default)
			)
			(layer "B.Fab")
		)
		(fp_line
			(start -0.12065 -0.2794)
			(end -0.12065 -0.3048)
			(stroke
				(width 0.1)
				(type default)
			)
			(layer "B.Fab")
		)
		(fp_line
			(start -0.120396 0.2794)
			(end 0.12065 0.2794)
			(stroke
				(width 0.1)
				(type default)
			)
			(layer "B.Fab")
		)
		(fp_line
			(start -0.120396 0.3048)
			(end -0.120396 0.2794)
			(stroke
				(width 0.1)
				(type default)
			)
			(layer "B.Fab")
		)
		(fp_line
			(start 0.12065 -0.305054)
			(end 0.12065 -0.2794)
			(stroke
				(width 0.1)
				(type default)
			)
			(layer "B.Fab")
		)
		(fp_line
			(start 0.12065 -0.2794)
			(end -0.12065 -0.2794)
			(stroke
				(width 0.1)
				(type default)
			)
			(layer "B.Fab")
		)
		(fp_line
			(start 0.12065 0.2794)
			(end 0.12065 0.3048)
			(stroke
				(width 0.1)
				(type default)
			)
			(layer "B.Fab")
		)
		(fp_line
			(start 0.12065 0.3048)
			(end 0.67945 0.3048)
			(stroke
				(width 0.1)
				(type default)
			)
			(layer "B.Fab")
		)
		(fp_line
			(start 0.67945 -0.305054)
			(end 0.12065 -0.305054)
			(stroke
				(width 0.1)
				(type default)
			)
			(layer "B.Fab")
		)
		(fp_line
			(start 0.67945 0.3048)
			(end 0.67945 -0.305054)
			(stroke
				(width 0.1)
				(type default)
			)
			(layer "B.Fab")
		)
		(pad "1" smd circle
			(at 0.40005 0 180)
			(size 0 0)
			(layers "B.Cu" "B.Mask" "B.Paste")
			(net "P12V_AUX")
		)
		(pad "2" smd circle
			(at -0.40005 0 180)
			(size 0 0)
			(layers "B.Cu" "B.Mask" "B.Paste")
			(net "PVCCIN_CPU0_VIN_CSNIN")
		)
	)
	(footprint ""
		(layer "B.Cu")
		(at 520.044426 -153.203148 90)
		(property "Reference" "X5"
			(at 1.4732 2.650998 270)
			(unlocked yes)
			(layer "B.SilkS")
			(effects
				(font
					(size 0.7874 0.5842)
					(thickness 0.1524)
				)
				(justify left mirror)
			)
		)
		(property "Value" ""
			(at 0 0 90)
			(layer "B.Fab")
			(effects
				(font
					(size 1.27 1.27)
				)
				(justify mirror)
			)
		)
		(property "Device Type" "TP_TDR_4P_FTS_TH-TP_TDR_4P_DIPA"
			(at -1.30175 1.27 0)
			(unlocked yes)
			(layer "B.Fab")
			(hide yes)
			(effects
				(font
					(size 0.635 0.4064)
					(thickness 0.1524)
				)
				(justify mirror)
			)
		)
		(property "User Part Number" "N_A"
			(at -1.30175 1.27 0)
			(unlocked yes)
			(layer "Cmts.User")
			(hide yes)
			(effects
				(font
					(size 0.635 0.4064)
					(thickness 0.1524)
				)
				(justify mirror)
			)
		)
		(duplicate_pad_numbers_are_jumpers no)
		(fp_line
			(start 0 -1.27)
			(end 0 -0.635)
			(stroke
				(width 0.1524)
				(type default)
			)
			(layer "B.SilkS")
		)
		(fp_line
			(start -2.54 -1.27)
			(end 0 -1.27)
			(stroke
				(width 0.1524)
				(type default)
			)
			(layer "B.SilkS")
		)
		(fp_line
			(start -2.54 -1.1303)
			(end -2.54 -1.27)
			(stroke
				(width 0.1524)
				(type default)
			)
			(layer "B.SilkS")
		)
		(fp_line
			(start 0 0.635)
			(end 0 1.905)
			(stroke
				(width 0.1524)
				(type default)
			)
			(layer "B.SilkS")
		)
		(fp_line
			(start -2.54 1.4097)
			(end -2.54 1.1303)
			(stroke
				(width 0.1524)
				(type default)
			)
			(layer "B.SilkS")
		)
		(fp_line
			(start 0 3.175)
			(end 0 3.81)
			(stroke
				(width 0.1524)
				(type default)
			)
			(layer "B.SilkS")
		)
		(fp_line
			(start 0 3.81)
			(end -2.54 3.81)
			(stroke
				(width 0.1524)
				(type default)
			)
			(layer "B.SilkS")
		)
		(fp_line
			(start -2.54 3.81)
			(end -2.54 3.6703)
			(stroke
				(width 0.1524)
				(type default)
			)
			(layer "B.SilkS")
		)
		(fp_poly
			(pts
				(xy 2.76987 -0.972566) (xy 2.76987 0.551434) (xy 1.24587 -0.210566)
			)
			(stroke
				(width 0)
				(type default)
			)
			(fill yes)
			(layer "B.SilkS")
		)
		(fp_line
			(start 0 -1.27)
			(end 0 3.81)
			(stroke
				(width 0.1)
				(type default)
			)
			(layer "B.Fab")
		)
		(fp_line
			(start -2.54 -1.27)
			(end 0 -1.27)
			(stroke
				(width 0.1)
				(type default)
			)
			(layer "B.Fab")
		)
		(fp_line
			(start 0 3.81)
			(end -2.54 3.81)
			(stroke
				(width 0.1)
				(type default)
			)
			(layer "B.Fab")
		)
		(fp_line
			(start -2.54 3.81)
			(end -2.54 -1.27)
			(stroke
				(width 0.1)
				(type default)
			)
			(layer "B.Fab")
		)
		(fp_poly
			(pts
				(xy 0.761746 0) (xy 2.285746 -0.762) (xy 2.285746 0.762)
			)
			(stroke
				(width 0)
				(type default)
			)
			(fill yes)
			(layer "B.Fab")
		)
		(pad "1" thru_hole circle
			(at 0 0 270)
			(size 1.0033 1.0033)
			(drill 0.249936)
			(layers "*.Cu" "*.Mask")
			(remove_unused_layers no)
			(net "TDR_DIFF_85_IN4_DP")
			(clearance 0.10795)
			(padstack
				(mode front_inner_back)
				(layer "Inner"
					(shape circle)
					(size 0.8001 0.8001)
					(clearance 0.1524)
				)
				(layer "B.Cu"
					(shape circle)
					(size 1.0033 1.0033)
					(thermal_gap 0.10795)
					(clearance 0.10795)
				)
			)
		)
		(pad "2" thru_hole circle
			(at -2.54 0 270)
			(size 1.9939 1.9939)
			(drill 0.249936)
			(layers "*.Cu" "*.Mask")
			(remove_unused_layers no)
			(net "T1_GND")
			(clearance 0.10795)
			(padstack
				(mode front_inner_back)
				(layer "Inner"
					(shape circle)
					(size 0.8001 0.8001)
					(clearance 0.1524)
				)
				(layer "B.Cu"
					(shape circle)
					(size 1.9939 1.9939)
					(thermal_gap 0.10795)
					(clearance 0.10795)
				)
			)
		)
		(pad "3" thru_hole circle
			(at -2.54 2.54 270)
			(size 1.9939 1.9939)
			(drill 0.249936)
			(layers "*.Cu" "*.Mask")
			(remove_unused_layers no)
			(net "T1_GND")
			(clearance 0.10795)
			(padstack
				(mode front_inner_back)
				(layer "Inner"
					(shape circle)
					(size 0.8001 0.8001)
					(clearance 0.1524)
				)
				(layer "B.Cu"
					(shape circle)
					(size 1.9939 1.9939)
					(thermal_gap 0.10795)
					(clearance 0.10795)
				)
			)
		)
		(pad "4" thru_hole circle
			(at 0 2.54 270)
			(size 1.0033 1.0033)
			(drill 0.249936)
			(layers "*.Cu" "*.Mask")
			(remove_unused_layers no)
			(net "TDR_DIFF_85_IN4_DN")
			(clearance 0.10795)
			(padstack
				(mode front_inner_back)
				(layer "Inner"
					(shape circle)
					(size 0.8001 0.8001)
					(clearance 0.1524)
				)
				(layer "B.Cu"
					(shape circle)
					(size 1.0033 1.0033)
					(thermal_gap 0.10795)
					(clearance 0.10795)
				)
			)
		)
	)
)
